(kicad_pcb
	(version 20241229)
	(generator "pcbnew")
	(generator_version "9.0")
	(general
		(thickness 1.294)
		(legacy_teardrops no)
	)
	(paper "A3")
	(title_block
		(title "Kintex 410T devboard")
		(date "2024-04-03")
		(rev "1.1.2")
		(comment 9 "footprints 823-828 of 975")
	)
	(layers
		(0 "F.Cu" mixed)
		(4 "In1.Cu" power)
		(6 "In2.Cu" power)
		(8 "In3.Cu" mixed)
		(10 "In4.Cu" power)
		(12 "In5.Cu" mixed)
		(14 "In6.Cu" power)
		(16 "In7.Cu" mixed)
		(18 "In8.Cu" power)
		(2 "B.Cu" mixed)
		(9 "F.Adhes" user "F.Adhesive")
		(11 "B.Adhes" user "B.Adhesive")
		(13 "F.Paste" user)
		(15 "B.Paste" user)
		(5 "F.SilkS" user "F.Silkscreen")
		(7 "B.SilkS" user "B.Silkscreen")
		(1 "F.Mask" user)
		(3 "B.Mask" user)
		(17 "Dwgs.User" user "User.Drawings")
		(19 "Cmts.User" user "User.Comments")
		(21 "Eco1.User" user "User.Eco1")
		(23 "Eco2.User" user "User.Eco2")
		(25 "Edge.Cuts" user)
		(27 "Margin" user)
		(31 "F.CrtYd" user "F.Courtyard")
		(29 "B.CrtYd" user "B.Courtyard")
		(35 "F.Fab" user)
		(33 "B.Fab" user)
	)
	(footprint "antmicro-footprints:C_0402_1005Metric"
		(layer "B.Cu")
		(at 214 138.5)
		(descr "Capacitor SMD 0402")
		(tags "capacitor SMD 0402")
		(property "Reference" "C30"
			(at 1.1 -0.45 180)
			(layer "B.SilkS")
			(effects
				(font
					(size 0.7 0.7)
					(thickness 0.15)
				)
				(justify left bottom mirror)
			)
		)
		(property "Value" "C_100n_0402"
			(at 0 -1.169 180)
			(layer "B.Fab")
			(effects
				(font
					(size 0.7 0.7)
					(thickness 0.15)
				)
				(justify left bottom mirror)
			)
		)
		(property "Description" "SMD Multilayer Ceramic Capacitor, 0.1 µF, 50 V, 0402 [1005 Metric], ± 10%, X5R, GRM Series"
			(at 0 0 0)
			(layer "F.Fab")
			(hide yes)
			(effects
				(font
					(size 1.27 1.27)
					(thickness 0.15)
				)
			)
		)
		(property "Author" "Antmicro"
			(at 0 0 0)
			(layer "B.Fab")
			(hide yes)
			(effects
				(font
					(size 1 1)
					(thickness 0.15)
				)
				(justify mirror)
			)
		)
		(property "Dielectric" "X5R"
			(at 0 0 0)
			(layer "B.Fab")
			(hide yes)
			(effects
				(font
					(size 1 1)
					(thickness 0.15)
				)
				(justify mirror)
			)
		)
		(property "License" "Apache-2.0"
			(at 0 0 0)
			(layer "B.Fab")
			(hide yes)
			(effects
				(font
					(size 1 1)
					(thickness 0.15)
				)
				(justify mirror)
			)
		)
		(property "MPN" "GRM155R61H104KE14D"
			(at 0 0 0)
			(layer "B.Fab")
			(hide yes)
			(effects
				(font
					(size 1 1)
					(thickness 0.15)
				)
				(justify mirror)
			)
		)
		(property "Manufacturer" "Murata"
			(at 0 0 0)
			(layer "B.Fab")
			(hide yes)
			(effects
				(font
					(size 1 1)
					(thickness 0.15)
				)
				(justify mirror)
			)
		)
		(property "Val" "100n"
			(at 0 0 0)
			(layer "B.Fab")
			(hide yes)
			(effects
				(font
					(size 1 1)
					(thickness 0.15)
				)
				(justify mirror)
			)
		)
		(property "Voltage" "50V"
			(at 0 0 0)
			(layer "B.Fab")
			(hide yes)
			(effects
				(font
					(size 1 1)
					(thickness 0.15)
				)
				(justify mirror)
			)
		)
		(sheetname "FPGA Bank 12 & 13")
		(sheetfile "fpga-bank-12-13.kicad_sch")
		(attr smd)
		(fp_rect
			(start -0.925 0.47)
			(end 0.925 -0.47)
			(stroke
				(width 0.05)
				(type default)
			)
			(fill no)
			(layer "B.CrtYd")
		)
		(fp_line
			(start -0.494 -0.248)
			(end -0.494 0.25)
			(stroke
				(width 0.15)
				(type solid)
			)
			(layer "B.Fab")
		)
		(fp_line
			(start -0.494 0.25)
			(end 0.504 0.25)
			(stroke
				(width 0.15)
				(type solid)
			)
			(layer "B.Fab")
		)
		(fp_line
			(start 0.504 -0.248)
			(end -0.494 -0.248)
			(stroke
				(width 0.15)
				(type solid)
			)
			(layer "B.Fab")
		)
		(fp_line
			(start 0.504 0.25)
			(end 0.504 -0.248)
			(stroke
				(width 0.15)
				(type solid)
			)
			(layer "B.Fab")
		)
		(pad "1" smd roundrect
			(at -0.48 0)
			(size 0.59 0.64)
			(layers "B.Cu" "B.Mask" "B.Paste")
			(roundrect_rratio 0.25)
			(net 1 "GND")
			(pintype "passive")
		)
		(pad "2" smd roundrect
			(at 0.48 0)
			(size 0.59 0.64)
			(layers "B.Cu" "B.Mask" "B.Paste")
			(roundrect_rratio 0.25)
			(net 24 "+3V3")
			(pintype "passive")
		)
	)
	(footprint "antmicro-footprints:C_0201"
		(layer "B.Cu")
		(at 198.55 131.44)
		(descr "Capacitor SMD 0201")
		(tags "capacitor SMD 0201")
		(property "Reference" "C266"
			(at 23.525 -28.165 0)
			(layer "B.SilkS")
			(effects
				(font
					(size 0.7 0.7)
					(thickness 0.15)
				)
				(justify right bottom mirror)
			)
		)
		(property "Value" "C_100n_0201"
			(at 0 -1.4 0)
			(layer "B.Fab")
			(effects
				(font
					(size 0.7 0.7)
					(thickness 0.15)
				)
				(justify right bottom mirror)
			)
		)
		(property "Description" "SMD Multilayer Ceramic Capacitor, 0.1 µF, 6.3 V, 0201 [0603 Metric], ± 10%, X6S, CC Series"
			(at 0 0 0)
			(layer "F.Fab")
			(hide yes)
			(effects
				(font
					(size 1.27 1.27)
					(thickness 0.15)
				)
			)
		)
		(property "Author" "Antmicro"
			(at 0 0 0)
			(layer "B.Fab")
			(hide yes)
			(effects
				(font
					(size 1 1)
					(thickness 0.15)
				)
				(justify mirror)
			)
		)
		(property "Dielectric" ""
			(at 0 0 0)
			(layer "B.Fab")
			(hide yes)
			(effects
				(font
					(size 1 1)
					(thickness 0.15)
				)
				(justify mirror)
			)
		)
		(property "License" "Apache-2.0"
			(at 0 0 0)
			(layer "B.Fab")
			(hide yes)
			(effects
				(font
					(size 1 1)
					(thickness 0.15)
				)
				(justify mirror)
			)
		)
		(property "MPN" "CC0201KRX6S5BB104"
			(at 0 0 0)
			(layer "B.Fab")
			(hide yes)
			(effects
				(font
					(size 1 1)
					(thickness 0.15)
				)
				(justify mirror)
			)
		)
		(property "Manufacturer" "YAGEO"
			(at 0 0 0)
			(layer "B.Fab")
			(hide yes)
			(effects
				(font
					(size 1 1)
					(thickness 0.15)
				)
				(justify mirror)
			)
		)
		(property "Val" "100n"
			(at 0 0 0)
			(layer "B.Fab")
			(hide yes)
			(effects
				(font
					(size 1 1)
					(thickness 0.15)
				)
				(justify mirror)
			)
		)
		(property "Voltage" ""
			(at 0 0 0)
			(layer "B.Fab")
			(hide yes)
			(effects
				(font
					(size 1 1)
					(thickness 0.15)
				)
				(justify mirror)
			)
		)
		(sheetname "FPGA Config")
		(sheetfile "fpga-config.kicad_sch")
		(attr smd)
		(fp_rect
			(start -0.7 0.35)
			(end 0.7 -0.35)
			(stroke
				(width 0.05)
				(type default)
			)
			(fill no)
			(layer "B.CrtYd")
		)
		(fp_rect
			(start 0.3 -0.15)
			(end -0.301 0.149)
			(stroke
				(width 0.15)
				(type solid)
			)
			(fill no)
			(layer "B.Fab")
		)
		(pad "" smd roundrect
			(at -0.349 0.002)
			(size 0.318 0.36)
			(layers "B.Paste")
			(roundrect_rratio 0.25)
		)
		(pad "" smd roundrect
			(at 0.341 0.002)
			(size 0.318 0.36)
			(layers "B.Paste")
			(roundrect_rratio 0.25)
		)
		(pad "1" smd roundrect
			(at -0.321 0.002)
			(size 0.46 0.4)
			(layers "B.Cu" "B.Mask")
			(roundrect_rratio 0.25)
			(net 870 "VREFN")
			(pintype "passive")
		)
		(pad "2" smd roundrect
			(at 0.32 0.002)
			(size 0.46 0.4)
			(layers "B.Cu" "B.Mask")
			(roundrect_rratio 0.25)
			(net 649 "VREFP")
			(pintype "passive")
		)
	)
	(footprint "antmicro-footprints:C_0603_1608Metric"
		(layer "B.Cu")
		(at 195.5 130)
		(descr "Capacitor SMD 0603")
		(tags "capacitor 0603")
		(property "Reference" "C51"
			(at 21.975 -28.05 0)
			(layer "B.SilkS")
			(effects
				(font
					(size 0.7 0.7)
					(thickness 0.15)
				)
				(justify right bottom mirror)
			)
		)
		(property "Value" "C_47u_0603"
			(at 0 -1.6 0)
			(layer "B.Fab")
			(effects
				(font
					(size 0.7 0.7)
					(thickness 0.15)
				)
				(justify right bottom mirror)
			)
		)
		(property "Description" "SMD Multilayer Ceramic Capacitor, 47 µF, 6.3 V, 0603 [1608 Metric], ± 20%, X5R, GRM Series"
			(at 0 0 0)
			(layer "F.Fab")
			(hide yes)
			(effects
				(font
					(size 1.27 1.27)
					(thickness 0.15)
				)
			)
		)
		(property "Author" "Antmicro"
			(at 0 0 0)
			(layer "B.Fab")
			(hide yes)
			(effects
				(font
					(size 1 1)
					(thickness 0.15)
				)
				(justify mirror)
			)
		)
		(property "Dielectric" ""
			(at 0 0 0)
			(layer "B.Fab")
			(hide yes)
			(effects
				(font
					(size 1 1)
					(thickness 0.15)
				)
				(justify mirror)
			)
		)
		(property "License" "Apache-2.0"
			(at 0 0 0)
			(layer "B.Fab")
			(hide yes)
			(effects
				(font
					(size 1 1)
					(thickness 0.15)
				)
				(justify mirror)
			)
		)
		(property "MPN" "GRM188R60J476ME15D"
			(at 0 0 0)
			(layer "B.Fab")
			(hide yes)
			(effects
				(font
					(size 1 1)
					(thickness 0.15)
				)
				(justify mirror)
			)
		)
		(property "Manufacturer" "Murata"
			(at 0 0 0)
			(layer "B.Fab")
			(hide yes)
			(effects
				(font
					(size 1 1)
					(thickness 0.15)
				)
				(justify mirror)
			)
		)
		(property "Val" "47u"
			(at 0 0 0)
			(layer "B.Fab")
			(hide yes)
			(effects
				(font
					(size 1 1)
					(thickness 0.15)
				)
				(justify mirror)
			)
		)
		(property "Voltage" ""
			(at 0 0 0)
			(layer "B.Fab")
			(hide yes)
			(effects
				(font
					(size 1 1)
					(thickness 0.15)
				)
				(justify mirror)
			)
		)
		(sheetname "FPGA supply")
		(sheetfile "fpga-supply.kicad_sch")
		(attr smd)
		(fp_line
			(start -0.15 -0.4)
			(end 0.15 -0.4)
			(stroke
				(width 0.15)
				(type solid)
			)
			(layer "B.SilkS")
		)
		(fp_line
			(start -0.15 0.4)
			(end 0.15 0.4)
			(stroke
				(width 0.15)
				(type solid)
			)
			(layer "B.SilkS")
		)
		(fp_rect
			(start -1.25 0.65)
			(end 1.25 -0.65)
			(stroke
				(width 0.05)
				(type solid)
			)
			(fill no)
			(layer "B.CrtYd")
		)
		(fp_rect
			(start -0.8 0.4)
			(end 0.8 -0.4)
			(stroke
				(width 0.15)
				(type solid)
			)
			(fill no)
			(layer "B.Fab")
		)
		(pad "1" smd roundrect
			(at -0.7 0)
			(size 0.8 1)
			(layers "B.Cu" "B.Mask" "B.Paste")
			(roundrect_rratio 0.2)
			(net 1 "GND")
			(pintype "passive")
		)
		(pad "2" smd roundrect
			(at 0.7 0)
			(size 0.8 1)
			(layers "B.Cu" "B.Mask" "B.Paste")
			(roundrect_rratio 0.2)
			(net 26 "+1V8")
			(pintype "passive")
		)
	)
	(footprint "antmicro-footprints:R_0402_1005Metric"
		(layer "B.Cu")
		(at 261.5 95.8)
		(descr "Resistor SMD 0402")
		(tags "resistor SMD 0402")
		(property "Reference" "R129"
			(at 1.375 1.25 180)
			(layer "B.SilkS")
			(effects
				(font
					(size 0.7 0.7)
					(thickness 0.15)
				)
				(justify left bottom mirror)
			)
		)
		(property "Value" "R_1k_0402"
			(at 0 -1.4 180)
			(layer "B.Fab")
			(effects
				(font
					(size 0.7 0.7)
					(thickness 0.15)
				)
				(justify left bottom mirror)
			)
		)
		(property "Description" "SMD Chip Resistor, 1 kohm, ± 1%, 63 mW, 0402 [1005 Metric], Thick Film, General Purpose"
			(at 0 0 0)
			(layer "F.Fab")
			(hide yes)
			(effects
				(font
					(size 1.27 1.27)
					(thickness 0.15)
				)
			)
		)
		(property "Author" "Antmicro"
			(at 0 0 0)
			(layer "B.Fab")
			(hide yes)
			(effects
				(font
					(size 1 1)
					(thickness 0.15)
				)
				(justify mirror)
			)
		)
		(property "License" "Apache-2.0"
			(at 0 0 0)
			(layer "B.Fab")
			(hide yes)
			(effects
				(font
					(size 1 1)
					(thickness 0.15)
				)
				(justify mirror)
			)
		)
		(property "MPN" "CR0402-FX-1001GLF"
			(at 0 0 0)
			(layer "B.Fab")
			(hide yes)
			(effects
				(font
					(size 1 1)
					(thickness 0.15)
				)
				(justify mirror)
			)
		)
		(property "Manufacturer" "Bourns"
			(at 0 0 0)
			(layer "B.Fab")
			(hide yes)
			(effects
				(font
					(size 1 1)
					(thickness 0.15)
				)
				(justify mirror)
			)
		)
		(property "Tolerance" "1%"
			(at 0 0 0)
			(layer "B.Fab")
			(hide yes)
			(effects
				(font
					(size 1 1)
					(thickness 0.15)
				)
				(justify mirror)
			)
		)
		(property "Val" "1k"
			(at 0 0 0)
			(layer "B.Fab")
			(hide yes)
			(effects
				(font
					(size 1 1)
					(thickness 0.15)
				)
				(justify mirror)
			)
		)
		(sheetname "User GPIO + LED + button + DIP switch")
		(sheetfile "user-gpio.kicad_sch")
		(attr smd)
		(fp_rect
			(start -0.925 0.47)
			(end 0.925 -0.47)
			(stroke
				(width 0.05)
				(type default)
			)
			(fill no)
			(layer "B.CrtYd")
		)
		(fp_rect
			(start -0.5 0.25)
			(end 0.5 -0.25)
			(stroke
				(width 0.15)
				(type solid)
			)
			(fill no)
			(layer "B.Fab")
		)
		(pad "1" smd roundrect
			(at -0.48 0)
			(size 0.59 0.64)
			(layers "B.Cu" "B.Mask" "B.Paste")
			(roundrect_rratio 0.25)
			(net 24 "+3V3")
			(pintype "passive")
		)
		(pad "2" smd roundrect
			(at 0.48 0)
			(size 0.59 0.64)
			(layers "B.Cu" "B.Mask" "B.Paste")
			(roundrect_rratio 0.25)
			(net 785 "Net-(D23-A)")
			(pintype "passive")
		)
	)
	(footprint "antmicro-footprints:C_0402_1005Metric"
		(layer "B.Cu")
		(at 194.5 143 90)
		(descr "Capacitor SMD 0402")
		(tags "capacitor SMD 0402")
		(property "Reference" "C90"
			(at 1.075 -0.425 270)
			(layer "B.SilkS")
			(effects
				(font
					(size 0.7 0.7)
					(thickness 0.15)
				)
				(justify left bottom mirror)
			)
		)
		(property "Value" "C_100n_0402"
			(at 0 -1.169 270)
			(layer "B.Fab")
			(effects
				(font
					(size 0.7 0.7)
					(thickness 0.15)
				)
				(justify left bottom mirror)
			)
		)
		(property "Description" "SMD Multilayer Ceramic Capacitor, 0.1 µF, 50 V, 0402 [1005 Metric], ± 10%, X5R, GRM Series"
			(at 0 0 90)
			(layer "F.Fab")
			(hide yes)
			(effects
				(font
					(size 1.27 1.27)
					(thickness 0.15)
				)
			)
		)
		(property "Author" "Antmicro"
			(at 337.5 -51.5 0)
			(layer "B.Fab")
			(hide yes)
			(effects
				(font
					(size 1 1)
					(thickness 0.15)
				)
				(justify mirror)
			)
		)
		(property "Dielectric" "X5R"
			(at 337.5 -51.5 0)
			(layer "B.Fab")
			(hide yes)
			(effects
				(font
					(size 1 1)
					(thickness 0.15)
				)
				(justify mirror)
			)
		)
		(property "License" "Apache-2.0"
			(at 337.5 -51.5 0)
			(layer "B.Fab")
			(hide yes)
			(effects
				(font
					(size 1 1)
					(thickness 0.15)
				)
				(justify mirror)
			)
		)
		(property "MPN" "GRM155R61H104KE14D"
			(at 337.5 -51.5 0)
			(layer "B.Fab")
			(hide yes)
			(effects
				(font
					(size 1 1)
					(thickness 0.15)
				)
				(justify mirror)
			)
		)
		(property "Manufacturer" "Murata"
			(at 337.5 -51.5 0)
			(layer "B.Fab")
			(hide yes)
			(effects
				(font
					(size 1 1)
					(thickness 0.15)
				)
				(justify mirror)
			)
		)
		(property "Val" "100n"
			(at 337.5 -51.5 0)
			(layer "B.Fab")
			(hide yes)
			(effects
				(font
					(size 1 1)
					(thickness 0.15)
				)
				(justify mirror)
			)
		)
		(property "Voltage" "50V"
			(at 337.5 -51.5 0)
			(layer "B.Fab")
			(hide yes)
			(effects
				(font
					(size 1 1)
					(thickness 0.15)
				)
				(justify mirror)
			)
		)
		(sheetname "FPGA Bank 33 & 34")
		(sheetfile "fpga-bank-33-34.kicad_sch")
		(attr smd)
		(fp_rect
			(start -0.925 0.47)
			(end 0.925 -0.47)
			(stroke
				(width 0.05)
				(type default)
			)
			(fill no)
			(layer "B.CrtYd")
		)
		(fp_line
			(start 0.504 -0.248)
			(end -0.494 -0.248)
			(stroke
				(width 0.15)
				(type solid)
			)
			(layer "B.Fab")
		)
		(fp_line
			(start -0.494 -0.248)
			(end -0.494 0.25)
			(stroke
				(width 0.15)
				(type solid)
			)
			(layer "B.Fab")
		)
		(fp_line
			(start 0.504 0.25)
			(end 0.504 -0.248)
			(stroke
				(width 0.15)
				(type solid)
			)
			(layer "B.Fab")
		)
		(fp_line
			(start -0.494 0.25)
			(end 0.504 0.25)
			(stroke
				(width 0.15)
				(type solid)
			)
			(layer "B.Fab")
		)
		(pad "1" smd roundrect
			(at -0.48 0 90)
			(size 0.59 0.64)
			(layers "B.Cu" "B.Mask" "B.Paste")
			(roundrect_rratio 0.25)
			(net 1 "GND")
			(pintype "passive")
		)
		(pad "2" smd roundrect
			(at 0.48 0 90)
			(size 0.59 0.64)
			(layers "B.Cu" "B.Mask" "B.Paste")
			(roundrect_rratio 0.25)
			(net 26 "+1V8")
			(pintype "passive")
		)
	)
	(footprint "antmicro-footprints:C_0402_1005Metric"
		(layer "B.Cu")
		(at 171.15 141.7 180)
		(descr "Capacitor SMD 0402")
		(tags "capacitor SMD 0402")
		(property "Reference" "C186"
			(at -0.975 0.475 0)
			(layer "B.SilkS")
			(effects
				(font
					(size 0.7 0.7)
					(thickness 0.15)
				)
				(justify left bottom mirror)
			)
		)
		(property "Value" "C_100n_0402"
			(at 0 -1.169 0)
			(layer "B.Fab")
			(effects
				(font
					(size 0.7 0.7)
					(thickness 0.15)
				)
				(justify left bottom mirror)
			)
		)
		(property "Description" "SMD Multilayer Ceramic Capacitor, 0.1 µF, 50 V, 0402 [1005 Metric], ± 10%, X5R, GRM Series"
			(at 0 0 180)
			(layer "F.Fab")
			(hide yes)
			(effects
				(font
					(size 1.27 1.27)
					(thickness 0.15)
				)
			)
		)
		(property "Author" "Antmicro"
			(at 342.3 283.4 0)
			(layer "B.Fab")
			(hide yes)
			(effects
				(font
					(size 1 1)
					(thickness 0.15)
				)
				(justify mirror)
			)
		)
		(property "Dielectric" "X5R"
			(at 342.3 283.4 0)
			(layer "B.Fab")
			(hide yes)
			(effects
				(font
					(size 1 1)
					(thickness 0.15)
				)
				(justify mirror)
			)
		)
		(property "License" "Apache-2.0"
			(at 342.3 283.4 0)
			(layer "B.Fab")
			(hide yes)
			(effects
				(font
					(size 1 1)
					(thickness 0.15)
				)
				(justify mirror)
			)
		)
		(property "MPN" "GRM155R61H104KE14D"
			(at 342.3 283.4 0)
			(layer "B.Fab")
			(hide yes)
			(effects
				(font
					(size 1 1)
					(thickness 0.15)
				)
				(justify mirror)
			)
		)
		(property "Manufacturer" "Murata"
			(at 342.3 283.4 0)
			(layer "B.Fab")
			(hide yes)
			(effects
				(font
					(size 1 1)
					(thickness 0.15)
				)
				(justify mirror)
			)
		)
		(property "Val" "100n"
			(at 342.3 283.4 0)
			(layer "B.Fab")
			(hide yes)
			(effects
				(font
					(size 1 1)
					(thickness 0.15)
				)
				(justify mirror)
			)
		)
		(property "Voltage" "50V"
			(at 342.3 283.4 0)
			(layer "B.Fab")
			(hide yes)
			(effects
				(font
					(size 1 1)
					(thickness 0.15)
				)
				(justify mirror)
			)
		)
		(sheetname "DRAM + SRAM")
		(sheetfile "ram.kicad_sch")
		(attr smd)
		(fp_rect
			(start -0.925 0.47)
			(end 0.925 -0.47)
			(stroke
				(width 0.05)
				(type default)
			)
			(fill no)
			(layer "B.CrtYd")
		)
		(fp_line
			(start 0.504 0.25)
			(end 0.504 -0.248)
			(stroke
				(width 0.15)
				(type solid)
			)
			(layer "B.Fab")
		)
		(fp_line
			(start 0.504 -0.248)
			(end -0.494 -0.248)
			(stroke
				(width 0.15)
				(type solid)
			)
			(layer "B.Fab")
		)
		(fp_line
			(start -0.494 0.25)
			(end 0.504 0.25)
			(stroke
				(width 0.15)
				(type solid)
			)
			(layer "B.Fab")
		)
		(fp_line
			(start -0.494 -0.248)
			(end -0.494 0.25)
			(stroke
				(width 0.15)
				(type solid)
			)
			(layer "B.Fab")
		)
		(pad "1" smd roundrect
			(at -0.48 0 180)
			(size 0.59 0.64)
			(layers "B.Cu" "B.Mask" "B.Paste")
			(roundrect_rratio 0.25)
			(net 1 "GND")
			(pintype "passive")
		)
		(pad "2" smd roundrect
			(at 0.48 0 180)
			(size 0.59 0.64)
			(layers "B.Cu" "B.Mask" "B.Paste")
			(roundrect_rratio 0.25)
			(net 11 "+0V675_VREF")
			(pintype "passive")
		)
	)
)
